(kicad_pcb
	(version 20260206)
	(generator "pcbnew")
	(generator_version "10.0")
	(general
		(thickness 1.6)
		(legacy_teardrops no)
	)
	(paper "A4")
	(title_block
		(title "04192023_DAF0TMB3IC0_F0TG_MB_C_brd_V02_OCP.brd")
		(comment 1 "Grand Teton / footprints 4039-4045 of 8354")
	)
	(layers
		(0 "F.Cu" signal "TOP")
		(4 "In1.Cu" signal "GND")
		(6 "In2.Cu" signal "IN1")
		(8 "In3.Cu" signal "GND1")
		(10 "In4.Cu" signal "IN2")
		(12 "In5.Cu" signal "GND2")
		(14 "In6.Cu" signal "IN3")
		(16 "In7.Cu" signal "GND3")
		(18 "In8.Cu" signal "VCC")
		(20 "In9.Cu" signal "VCC1")
		(22 "In10.Cu" signal "GND4")
		(24 "In11.Cu" signal "IN4")
		(26 "In12.Cu" signal "GND5")
		(28 "In13.Cu" signal "IN5")
		(30 "In14.Cu" signal "GND6")
		(32 "In15.Cu" signal "IN6")
		(34 "In16.Cu" signal "GND7")
		(2 "B.Cu" signal "BOTTOM")
		(9 "F.Adhes" user "F.Adhesive")
		(11 "B.Adhes" user "B.Adhesive")
		(13 "F.Paste" user "Package Geometry/Pastemask Top")
		(15 "B.Paste" user "Package Geometry/Pastemask Bottom")
		(5 "F.SilkS" user "Ref Des/Silkscreen Top")
		(7 "B.SilkS" user "Ref Des/Silkscreen Bottom")
		(1 "F.Mask" user "Board Geometry/Soldermask Top")
		(3 "B.Mask" user "Board Geometry/Soldermask Bottom")
		(17 "Dwgs.User" user "User.Drawings")
		(19 "Cmts.User" user "User.Comments")
		(21 "Eco1.User" user "User.Eco1")
		(23 "Eco2.User" user "User.Eco2")
		(25 "Edge.Cuts" user "Board Geometry/Outline")
		(27 "Margin" user)
		(31 "F.CrtYd" user "Package Geometry/Place Bound Top")
		(29 "B.CrtYd" user "Package Geometry/Place Bound Bottom")
		(35 "F.Fab" user "Ref Des/Assembly Top")
		(33 "B.Fab" user "Ref Des/Assembly Bottom")
	)
	(footprint ""
		(layer "F.Cu")
		(at 88.895936 -178.024028 90)
		(property "Reference" "PC271"
			(at 0 0 90)
			(layer "F.SilkS")
			(hide yes)
			(effects
				(font
					(size 1.27 1.27)
				)
			)
		)
		(property "Value" ""
			(at 0 0 90)
			(layer "F.Fab")
			(effects
				(font
					(size 1.27 1.27)
				)
			)
		)
		(duplicate_pad_numbers_are_jumpers no)
		(fp_line
			(start 0.7874 -0.4064)
			(end 0.7874 0.4064)
			(stroke
				(width 0.1524)
				(type default)
			)
			(layer "F.SilkS")
		)
		(fp_line
			(start -0.7874 -0.4064)
			(end 0.7874 -0.4064)
			(stroke
				(width 0.1524)
				(type default)
			)
			(layer "F.SilkS")
		)
		(fp_line
			(start 0.7874 0.4064)
			(end -0.7874 0.4064)
			(stroke
				(width 0.1524)
				(type default)
			)
			(layer "F.SilkS")
		)
		(fp_line
			(start -0.7874 0.4064)
			(end -0.7874 -0.4064)
			(stroke
				(width 0.1524)
				(type default)
			)
			(layer "F.SilkS")
		)
		(fp_line
			(start -0.12065 -0.305054)
			(end -0.12065 -0.2794)
			(stroke
				(width 0.1)
				(type default)
			)
			(layer "F.Fab")
		)
		(fp_line
			(start -0.67945 -0.305054)
			(end -0.12065 -0.305054)
			(stroke
				(width 0.1)
				(type default)
			)
			(layer "F.Fab")
		)
		(fp_line
			(start 0.67945 -0.3048)
			(end 0.67945 0.3048)
			(stroke
				(width 0.1)
				(type default)
			)
			(layer "F.Fab")
		)
		(fp_line
			(start 0.12065 -0.3048)
			(end 0.67945 -0.3048)
			(stroke
				(width 0.1)
				(type default)
			)
			(layer "F.Fab")
		)
		(fp_line
			(start 0.12065 -0.2794)
			(end 0.12065 -0.3048)
			(stroke
				(width 0.1)
				(type default)
			)
			(layer "F.Fab")
		)
		(fp_line
			(start -0.12065 -0.2794)
			(end 0.12065 -0.2794)
			(stroke
				(width 0.1)
				(type default)
			)
			(layer "F.Fab")
		)
		(fp_line
			(start 0.120396 0.2794)
			(end -0.12065 0.2794)
			(stroke
				(width 0.1)
				(type default)
			)
			(layer "F.Fab")
		)
		(fp_line
			(start -0.12065 0.2794)
			(end -0.12065 0.3048)
			(stroke
				(width 0.1)
				(type default)
			)
			(layer "F.Fab")
		)
		(fp_line
			(start 0.67945 0.3048)
			(end 0.120396 0.3048)
			(stroke
				(width 0.1)
				(type default)
			)
			(layer "F.Fab")
		)
		(fp_line
			(start 0.120396 0.3048)
			(end 0.120396 0.2794)
			(stroke
				(width 0.1)
				(type default)
			)
			(layer "F.Fab")
		)
		(fp_line
			(start -0.12065 0.3048)
			(end -0.67945 0.3048)
			(stroke
				(width 0.1)
				(type default)
			)
			(layer "F.Fab")
		)
		(fp_line
			(start -0.67945 0.3048)
			(end -0.67945 -0.305054)
			(stroke
				(width 0.1)
				(type default)
			)
			(layer "F.Fab")
		)
		(pad "1" smd circle
			(at -0.40005 0 90)
			(size 0 0)
			(layers "F.Cu" "F.Mask" "F.Paste")
			(net "SW_PVDDCR_CPU0_P1_BOOT2_RC")
		)
		(pad "2" smd circle
			(at 0.40005 0 90)
			(size 0 0)
			(layers "F.Cu" "F.Mask" "F.Paste")
			(net "SW_PVDDCR_CPU0_P1_PH2")
		)
	)
	(footprint ""
		(layer "F.Cu")
		(at 157.698186 -347.260164)
		(property "Reference" "R8146"
			(at 0 0 0)
			(layer "F.SilkS")
			(hide yes)
			(effects
				(font
					(size 1.27 1.27)
				)
			)
		)
		(property "Value" ""
			(at 0 0 0)
			(layer "F.Fab")
			(effects
				(font
					(size 1.27 1.27)
				)
			)
		)
		(duplicate_pad_numbers_are_jumpers no)
		(fp_line
			(start -0.7874 -0.4064)
			(end 0.7874 -0.4064)
			(stroke
				(width 0.1524)
				(type default)
			)
			(layer "F.SilkS")
		)
		(fp_line
			(start -0.7874 0.4064)
			(end -0.7874 -0.4064)
			(stroke
				(width 0.1524)
				(type default)
			)
			(layer "F.SilkS")
		)
		(fp_line
			(start 0.7874 -0.4064)
			(end 0.7874 0.4064)
			(stroke
				(width 0.1524)
				(type default)
			)
			(layer "F.SilkS")
		)
		(fp_line
			(start 0.7874 0.4064)
			(end -0.7874 0.4064)
			(stroke
				(width 0.1524)
				(type default)
			)
			(layer "F.SilkS")
		)
		(fp_line
			(start -0.67945 -0.305054)
			(end -0.12065 -0.305054)
			(stroke
				(width 0.1)
				(type default)
			)
			(layer "F.Fab")
		)
		(fp_line
			(start -0.67945 0.3048)
			(end -0.67945 -0.305054)
			(stroke
				(width 0.1)
				(type default)
			)
			(layer "F.Fab")
		)
		(fp_line
			(start -0.12065 -0.305054)
			(end -0.12065 -0.2794)
			(stroke
				(width 0.1)
				(type default)
			)
			(layer "F.Fab")
		)
		(fp_line
			(start -0.12065 -0.2794)
			(end 0.12065 -0.2794)
			(stroke
				(width 0.1)
				(type default)
			)
			(layer "F.Fab")
		)
		(fp_line
			(start -0.12065 0.2794)
			(end -0.12065 0.3048)
			(stroke
				(width 0.1)
				(type default)
			)
			(layer "F.Fab")
		)
		(fp_line
			(start -0.12065 0.3048)
			(end -0.67945 0.3048)
			(stroke
				(width 0.1)
				(type default)
			)
			(layer "F.Fab")
		)
		(fp_line
			(start 0.120396 0.2794)
			(end -0.12065 0.2794)
			(stroke
				(width 0.1)
				(type default)
			)
			(layer "F.Fab")
		)
		(fp_line
			(start 0.120396 0.3048)
			(end 0.120396 0.2794)
			(stroke
				(width 0.1)
				(type default)
			)
			(layer "F.Fab")
		)
		(fp_line
			(start 0.12065 -0.3048)
			(end 0.67945 -0.3048)
			(stroke
				(width 0.1)
				(type default)
			)
			(layer "F.Fab")
		)
		(fp_line
			(start 0.12065 -0.2794)
			(end 0.12065 -0.3048)
			(stroke
				(width 0.1)
				(type default)
			)
			(layer "F.Fab")
		)
		(fp_line
			(start 0.67945 -0.3048)
			(end 0.67945 0.3048)
			(stroke
				(width 0.1)
				(type default)
			)
			(layer "F.Fab")
		)
		(fp_line
			(start 0.67945 0.3048)
			(end 0.120396 0.3048)
			(stroke
				(width 0.1)
				(type default)
			)
			(layer "F.Fab")
		)
		(pad "1" smd circle
			(at -0.40005 0)
			(size 0 0)
			(layers "F.Cu" "F.Mask" "F.Paste")
			(net "P3V3_AUX")
		)
		(pad "2" smd circle
			(at 0.40005 0)
			(size 0 0)
			(layers "F.Cu" "F.Mask" "F.Paste")
			(net "PVDD11_S3_P1_VDDIO")
		)
	)
	(footprint ""
		(layer "F.Cu")
		(at 358.96169 -390.1694 180)
		(property "Reference" "R1395"
			(at 0 0 180)
			(layer "F.SilkS")
			(hide yes)
			(effects
				(font
					(size 1.27 1.27)
				)
			)
		)
		(property "Value" ""
			(at 0 0 180)
			(layer "F.Fab")
			(effects
				(font
					(size 1.27 1.27)
				)
			)
		)
		(duplicate_pad_numbers_are_jumpers no)
		(fp_line
			(start 0.32512 0.175006)
			(end -0.32512 0.175006)
			(stroke
				(width 0.1)
				(type default)
			)
			(layer "F.Fab")
		)
		(fp_line
			(start 0.32512 -0.175006)
			(end 0.32512 0.175006)
			(stroke
				(width 0.1)
				(type default)
			)
			(layer "F.Fab")
		)
		(fp_line
			(start -0.32512 0.175006)
			(end -0.32512 -0.175006)
			(stroke
				(width 0.1)
				(type default)
			)
			(layer "F.Fab")
		)
		(fp_line
			(start -0.32512 -0.175006)
			(end 0.32512 -0.175006)
			(stroke
				(width 0.1)
				(type default)
			)
			(layer "F.Fab")
		)
		(pad "1" smd rect
			(at -0.2667 0 180)
			(size 0.3048 0.381)
			(layers "F.Cu" "F.Mask" "F.Paste")
			(net "CLKREQ_RT_CPU0_P1_N")
		)
		(pad "2" smd rect
			(at 0.2667 0)
			(size 0.3048 0.381)
			(layers "F.Cu" "F.Mask" "F.Paste")
			(net "GND")
		)
	)
	(footprint ""
		(layer "F.Cu")
		(at 84.832952 -151.207216 -90)
		(property "Reference" "PC6002"
			(at 0 0 270)
			(layer "F.SilkS")
			(hide yes)
			(effects
				(font
					(size 1.27 1.27)
				)
			)
		)
		(property "Value" ""
			(at 0 0 270)
			(layer "F.Fab")
			(effects
				(font
					(size 1.27 1.27)
				)
			)
		)
		(duplicate_pad_numbers_are_jumpers no)
		(fp_line
			(start -0.7874 0.4064)
			(end -0.7874 -0.4064)
			(stroke
				(width 0.1524)
				(type default)
			)
			(layer "F.SilkS")
		)
		(fp_line
			(start 0.7874 0.4064)
			(end -0.7874 0.4064)
			(stroke
				(width 0.1524)
				(type default)
			)
			(layer "F.SilkS")
		)
		(fp_line
			(start -0.7874 -0.4064)
			(end 0.7874 -0.4064)
			(stroke
				(width 0.1524)
				(type default)
			)
			(layer "F.SilkS")
		)
		(fp_line
			(start 0.7874 -0.4064)
			(end 0.7874 0.4064)
			(stroke
				(width 0.1524)
				(type default)
			)
			(layer "F.SilkS")
		)
		(fp_line
			(start -0.67945 0.3048)
			(end -0.67945 -0.305054)
			(stroke
				(width 0.1)
				(type default)
			)
			(layer "F.Fab")
		)
		(fp_line
			(start -0.12065 0.3048)
			(end -0.67945 0.3048)
			(stroke
				(width 0.1)
				(type default)
			)
			(layer "F.Fab")
		)
		(fp_line
			(start 0.120396 0.3048)
			(end 0.120396 0.2794)
			(stroke
				(width 0.1)
				(type default)
			)
			(layer "F.Fab")
		)
		(fp_line
			(start 0.67945 0.3048)
			(end 0.120396 0.3048)
			(stroke
				(width 0.1)
				(type default)
			)
			(layer "F.Fab")
		)
		(fp_line
			(start -0.12065 0.2794)
			(end -0.12065 0.3048)
			(stroke
				(width 0.1)
				(type default)
			)
			(layer "F.Fab")
		)
		(fp_line
			(start 0.120396 0.2794)
			(end -0.12065 0.2794)
			(stroke
				(width 0.1)
				(type default)
			)
			(layer "F.Fab")
		)
		(fp_line
			(start -0.12065 -0.2794)
			(end 0.12065 -0.2794)
			(stroke
				(width 0.1)
				(type default)
			)
			(layer "F.Fab")
		)
		(fp_line
			(start 0.12065 -0.2794)
			(end 0.12065 -0.3048)
			(stroke
				(width 0.1)
				(type default)
			)
			(layer "F.Fab")
		)
		(fp_line
			(start 0.12065 -0.3048)
			(end 0.67945 -0.3048)
			(stroke
				(width 0.1)
				(type default)
			)
			(layer "F.Fab")
		)
		(fp_line
			(start 0.67945 -0.3048)
			(end 0.67945 0.3048)
			(stroke
				(width 0.1)
				(type default)
			)
			(layer "F.Fab")
		)
		(fp_line
			(start -0.67945 -0.305054)
			(end -0.12065 -0.305054)
			(stroke
				(width 0.1)
				(type default)
			)
			(layer "F.Fab")
		)
		(fp_line
			(start -0.12065 -0.305054)
			(end -0.12065 -0.2794)
			(stroke
				(width 0.1)
				(type default)
			)
			(layer "F.Fab")
		)
		(pad "1" smd circle
			(at -0.40005 0 270)
			(size 0 0)
			(layers "F.Cu" "F.Mask" "F.Paste")
			(net "P12V_AUX")
		)
		(pad "2" smd circle
			(at 0.40005 0 270)
			(size 0 0)
			(layers "F.Cu" "F.Mask" "F.Paste")
			(net "GND")
		)
	)
	(footprint ""
		(layer "F.Cu")
		(at 15.508478 -16.099536 90)
		(property "Reference" "C678"
			(at 0 0 90)
			(layer "F.SilkS")
			(hide yes)
			(effects
				(font
					(size 1.27 1.27)
				)
			)
		)
		(property "Value" ""
			(at 0 0 90)
			(layer "F.Fab")
			(effects
				(font
					(size 1.27 1.27)
				)
			)
		)
		(duplicate_pad_numbers_are_jumpers no)
		(fp_line
			(start 0.299974 -0.150114)
			(end 0.299974 0.150114)
			(stroke
				(width 0.1)
				(type default)
			)
			(layer "F.Fab")
		)
		(fp_line
			(start -0.299974 -0.150114)
			(end 0.299974 -0.150114)
			(stroke
				(width 0.1)
				(type default)
			)
			(layer "F.Fab")
		)
		(fp_line
			(start 0.299974 0.150114)
			(end -0.299974 0.150114)
			(stroke
				(width 0.1)
				(type default)
			)
			(layer "F.Fab")
		)
		(fp_line
			(start -0.299974 0.150114)
			(end -0.299974 -0.150114)
			(stroke
				(width 0.1)
				(type default)
			)
			(layer "F.Fab")
		)
		(pad "1" smd rect
			(at -0.2667 0 90)
			(size 0.3048 0.381)
			(layers "F.Cu" "F.Mask" "F.Paste")
			(net "P5E_CPU1_G1_TX_C_DN<15>")
		)
		(pad "2" smd rect
			(at 0.2667 0 90)
			(size 0.3048 0.381)
			(layers "F.Cu" "F.Mask" "F.Paste")
			(net "P5E_CPU1_G1_TX_DN<15>")
		)
	)
	(footprint ""
		(layer "F.Cu")
		(at 288.331148 -344.982038 90)
		(property "Reference" "PR223"
			(at 0 0 90)
			(layer "F.SilkS")
			(hide yes)
			(effects
				(font
					(size 1.27 1.27)
				)
			)
		)
		(property "Value" ""
			(at 0 0 90)
			(layer "F.Fab")
			(effects
				(font
					(size 1.27 1.27)
				)
			)
		)
		(duplicate_pad_numbers_are_jumpers no)
		(fp_line
			(start 0.7874 -0.4064)
			(end 0.7874 0.4064)
			(stroke
				(width 0.1524)
				(type default)
			)
			(layer "F.SilkS")
		)
		(fp_line
			(start -0.7874 -0.4064)
			(end 0.7874 -0.4064)
			(stroke
				(width 0.1524)
				(type default)
			)
			(layer "F.SilkS")
		)
		(fp_line
			(start 0.7874 0.4064)
			(end -0.7874 0.4064)
			(stroke
				(width 0.1524)
				(type default)
			)
			(layer "F.SilkS")
		)
		(fp_line
			(start -0.7874 0.4064)
			(end -0.7874 -0.4064)
			(stroke
				(width 0.1524)
				(type default)
			)
			(layer "F.SilkS")
		)
		(fp_line
			(start -0.12065 -0.305054)
			(end -0.12065 -0.2794)
			(stroke
				(width 0.1)
				(type default)
			)
			(layer "F.Fab")
		)
		(fp_line
			(start -0.67945 -0.305054)
			(end -0.12065 -0.305054)
			(stroke
				(width 0.1)
				(type default)
			)
			(layer "F.Fab")
		)
		(fp_line
			(start 0.67945 -0.3048)
			(end 0.67945 0.3048)
			(stroke
				(width 0.1)
				(type default)
			)
			(layer "F.Fab")
		)
		(fp_line
			(start 0.12065 -0.3048)
			(end 0.67945 -0.3048)
			(stroke
				(width 0.1)
				(type default)
			)
			(layer "F.Fab")
		)
		(fp_line
			(start 0.12065 -0.2794)
			(end 0.12065 -0.3048)
			(stroke
				(width 0.1)
				(type default)
			)
			(layer "F.Fab")
		)
		(fp_line
			(start -0.12065 -0.2794)
			(end 0.12065 -0.2794)
			(stroke
				(width 0.1)
				(type default)
			)
			(layer "F.Fab")
		)
		(fp_line
			(start 0.120396 0.2794)
			(end -0.12065 0.2794)
			(stroke
				(width 0.1)
				(type default)
			)
			(layer "F.Fab")
		)
		(fp_line
			(start -0.12065 0.2794)
			(end -0.12065 0.3048)
			(stroke
				(width 0.1)
				(type default)
			)
			(layer "F.Fab")
		)
		(fp_line
			(start 0.67945 0.3048)
			(end 0.120396 0.3048)
			(stroke
				(width 0.1)
				(type default)
			)
			(layer "F.Fab")
		)
		(fp_line
			(start 0.120396 0.3048)
			(end 0.120396 0.2794)
			(stroke
				(width 0.1)
				(type default)
			)
			(layer "F.Fab")
		)
		(fp_line
			(start -0.12065 0.3048)
			(end -0.67945 0.3048)
			(stroke
				(width 0.1)
				(type default)
			)
			(layer "F.Fab")
		)
		(fp_line
			(start -0.67945 0.3048)
			(end -0.67945 -0.305054)
			(stroke
				(width 0.1)
				(type default)
			)
			(layer "F.Fab")
		)
		(pad "1" smd circle
			(at -0.40005 0 90)
			(size 0 0)
			(layers "F.Cu" "F.Mask" "F.Paste")
			(net "SW_PVDDIO_P0_SW2_RC")
		)
		(pad "2" smd circle
			(at 0.40005 0 90)
			(size 0 0)
			(layers "F.Cu" "F.Mask" "F.Paste")
			(net "GND")
		)
	)
	(footprint ""
		(layer "F.Cu")
		(at 274.117562 -351.927922)
		(property "Reference" "PR105"
			(at 0 0 0)
			(layer "F.SilkS")
			(hide yes)
			(effects
				(font
					(size 1.27 1.27)
				)
			)
		)
		(property "Value" ""
			(at 0 0 0)
			(layer "F.Fab")
			(effects
				(font
					(size 1.27 1.27)
				)
			)
		)
		(duplicate_pad_numbers_are_jumpers no)
		(fp_line
			(start -0.7874 -0.4064)
			(end 0.7874 -0.4064)
			(stroke
				(width 0.1524)
				(type default)
			)
			(layer "F.SilkS")
		)
		(fp_line
			(start -0.7874 0.4064)
			(end -0.7874 -0.4064)
			(stroke
				(width 0.1524)
				(type default)
			)
			(layer "F.SilkS")
		)
		(fp_line
			(start 0.7874 -0.4064)
			(end 0.7874 0.4064)
			(stroke
				(width 0.1524)
				(type default)
			)
			(layer "F.SilkS")
		)
		(fp_line
			(start 0.7874 0.4064)
			(end -0.7874 0.4064)
			(stroke
				(width 0.1524)
				(type default)
			)
			(layer "F.SilkS")
		)
		(fp_line
			(start -0.67945 -0.305054)
			(end -0.12065 -0.305054)
			(stroke
				(width 0.1)
				(type default)
			)
			(layer "F.Fab")
		)
		(fp_line
			(start -0.67945 0.3048)
			(end -0.67945 -0.305054)
			(stroke
				(width 0.1)
				(type default)
			)
			(layer "F.Fab")
		)
		(fp_line
			(start -0.12065 -0.305054)
			(end -0.12065 -0.2794)
			(stroke
				(width 0.1)
				(type default)
			)
			(layer "F.Fab")
		)
		(fp_line
			(start -0.12065 -0.2794)
			(end 0.12065 -0.2794)
			(stroke
				(width 0.1)
				(type default)
			)
			(layer "F.Fab")
		)
		(fp_line
			(start -0.12065 0.2794)
			(end -0.12065 0.3048)
			(stroke
				(width 0.1)
				(type default)
			)
			(layer "F.Fab")
		)
		(fp_line
			(start -0.12065 0.3048)
			(end -0.67945 0.3048)
			(stroke
				(width 0.1)
				(type default)
			)
			(layer "F.Fab")
		)
		(fp_line
			(start 0.120396 0.2794)
			(end -0.12065 0.2794)
			(stroke
				(width 0.1)
				(type default)
			)
			(layer "F.Fab")
		)
		(fp_line
			(start 0.120396 0.3048)
			(end 0.120396 0.2794)
			(stroke
				(width 0.1)
				(type default)
			)
			(layer "F.Fab")
		)
		(fp_line
			(start 0.12065 -0.3048)
			(end 0.67945 -0.3048)
			(stroke
				(width 0.1)
				(type default)
			)
			(layer "F.Fab")
		)
		(fp_line
			(start 0.12065 -0.2794)
			(end 0.12065 -0.3048)
			(stroke
				(width 0.1)
				(type default)
			)
			(layer "F.Fab")
		)
		(fp_line
			(start 0.67945 -0.3048)
			(end 0.67945 0.3048)
			(stroke
				(width 0.1)
				(type default)
			)
			(layer "F.Fab")
		)
		(fp_line
			(start 0.67945 0.3048)
			(end 0.120396 0.3048)
			(stroke
				(width 0.1)
				(type default)
			)
			(layer "F.Fab")
		)
		(pad "1" smd circle
			(at -0.40005 0)
			(size 0 0)
			(layers "F.Cu" "F.Mask" "F.Paste")
			(net "PVDDIO_P0_LSET4")
		)
		(pad "2" smd circle
			(at 0.40005 0)
			(size 0 0)
			(layers "F.Cu" "F.Mask" "F.Paste")
			(net "GND")
		)
	)
)
